# T6G (Grand Teton) — schematic parts with pin connectivity, parts 2610–2610 of 8303; source: Cadence DE-HDL packaged netlist (pstxprt.dat, pstxnet.dat, pstchip.dat)

J30  SCONN288_DDR506112002KQ  IO  pkg DDR288S_1-1VXC  page 101
  1  VIN_BULK0  POWER  = P12V_MEM_CPU1
  2  RFU0  TRI  = NC
  3  VIN_MGMT  POWER  = P3V3_AUX
  4  HSCL  IN  = I3C_SPD_DDRD_CPU1_SCL
  5  HSDA  BI  = I3C_SPD_DDRD_CPU1_SDA
  6  VSS0  POWER  = GND
  7  DQ0_A  BI  = M_D_CPU1_SA_DQ<0>
  8  VSS1  POWER  = GND
  9  DQ1_A  BI  = M_D_CPU1_SA_DQ<1>
  10  VSS2  POWER  = GND
  11  DQS0_A_T  BI  = M_D_CPU1_SA_DQS_DP<0>
  12  DQS0_A_C  BI  = M_D_CPU1_SA_DQS_DN<0>
  13  VSS3  POWER  = GND
  14  DQ4_A  BI  = M_D_CPU1_SA_DQ<4>
  15  VSS4  POWER  = GND
  16  DQ5_A  BI  = M_D_CPU1_SA_DQ<5>
  17  VSS5  POWER  = GND
  18  DQ8_A  BI  = M_D_CPU1_SA_DQ<8>
  19  VSS6  POWER  = GND
  20  DQ9_A  BI  = M_D_CPU1_SA_DQ<9>
  21  VSS7  POWER  = GND
  22  DQS1_A_T  BI  = M_D_CPU1_SA_DQS_DP<1>
  23  DQS1_A_C  BI  = M_D_CPU1_SA_DQS_DN<1>
  24  VSS8  POWER  = GND
  25  DQ12_A  BI  = M_D_CPU1_SA_DQ<12>
  26  VSS9  POWER  = GND
  27  DQ13_A  BI  = M_D_CPU1_SA_DQ<13>
  28  VSS10  POWER  = GND
  29  DQ16_A  BI  = M_D_CPU1_SA_DQ<16>
  30  VSS11  POWER  = GND
  31  DQ17_A  BI  = M_D_CPU1_SA_DQ<17>
  32  VSS12  POWER  = GND
  33  DQS2_A_T  BI  = M_D_CPU1_SA_DQS_DP<2>
  34  DQS2_A_C  BI  = M_D_CPU1_SA_DQS_DN<2>
  35  VSS13  POWER  = GND
  36  DQ20_A  BI  = M_D_CPU1_SA_DQ<20>
  37  VSS14  POWER  = GND
  38  DQ21_A  BI  = M_D_CPU1_SA_DQ<21>
  39  VSS15  POWER  = GND
  40  DQ24_A  BI  = M_D_CPU1_SA_DQ<24>
  41  VSS16  POWER  = GND
  42  DQ25_A  BI  = M_D_CPU1_SA_DQ<25>
  43  VSS17  POWER  = GND
  44  DQS3_A_T  BI  = M_D_CPU1_SA_DQS_DP<3>
  45  DQS3_A_C  BI  = M_D_CPU1_SA_DQS_DN<3>
  46  VSS18  POWER  = GND
  47  DQ28_A  BI  = M_D_CPU1_SA_DQ<28>
  48  VSS19  POWER  = GND
  49  DQ29_A  BI  = M_D_CPU1_SA_DQ<29>
  50  VSS20  POWER  = GND
  51  CB0_A  BI  = M_D_CPU1_SA_CB<0>
  52  VSS21  POWER  = GND
  53  CB1_A  BI  = M_D_CPU1_SA_CB<1>
  54  VSS22  POWER  = GND
  55  DQS4_A_T  BI  = M_D_CPU1_SA_DQS_DP<4>
  56  DQS4_A_C  BI  = M_D_CPU1_SA_DQS_DN<4>
  57  VSS23  POWER  = GND
  58  CB4_A  BI  = M_D_CPU1_SA_CB<4>
  59  VSS24  POWER  = GND
  60  CB5_A  BI  = M_D_CPU1_SA_CB<5>
  61  VSS25  POWER  = GND
  62  ALERT_N  OUT  = M_D_CPU1_ALERT_N
  63  VSS26  POWER  = GND
  64  CS0_A_N  IN  = M_D_CPU1_SA_CS_N<0>
  65  VSS27  POWER  = GND
  66  CA0_A  IN  = M_D_CPU1_SA_CA<0>
  67  VSS28  POWER  = GND
  68  CA2_A  IN  = M_D_CPU1_SA_CA<2>
  69  VSS29  POWER  = GND
  70  CA4_A  IN  = M_D_CPU1_SA_CA<4>
  71  VSS30  POWER  = GND
  72  CA6_A  IN  = M_D_CPU1_SA_CA<6>
  73  VSS31  POWER  = GND
  74  PAR_A  IN  = M_D_CPU1_SA_PAR
  75  VSS32  POWER  = GND
  76  CA0_B  IN  = M_D_CPU1_SB_CA<0>
  77  VSS33  POWER  = GND
  78  CA2_B  IN  = M_D_CPU1_SB_CA<2>
  79  VSS34  POWER  = GND
  80  CA4_B  IN  = M_D_CPU1_SB_CA<4>
  81  VSS35  POWER  = GND
  82  CA6_B  IN  = M_D_CPU1_SB_CA<6>
  83  VSS36  POWER  = GND
  84  CS0_B_N  IN  = M_D_CPU1_SB_CS_N<0>
  85  VSS37  POWER  = GND
  86  \lbd||rsp_a_n\  OUT  = M_D_CPU1_SA_RSP<0>
  87  \lbs||rsp_b_n\  OUT  = M_D_CPU1_SB_RSP<0>
  88  VSS38  POWER  = GND
  89  CB4_B  BI  = M_D_CPU1_SB_CB<4>
  90  VSS39  POWER  = GND
  91  CB5_B  BI  = M_D_CPU1_SB_CB<5>
  92  VSS40  POWER  = GND
  93  \dqs9_b_t||tdqs9_b_t||dbi4_b_n\  BI  = M_D_CPU1_SB_DQS_DP<9>
  94  \dqs9_b_c||tdqs9_b_c\  BI  = M_D_CPU1_SB_DQS_DN<9>
  95  VSS41  POWER  = GND
  96  CB0_B  BI  = M_D_CPU1_SB_CB<0>
  97  VSS42  POWER  = GND
  98  CB1_B  BI  = M_D_CPU1_SB_CB<1>
  99  VSS43  POWER  = GND
  100  DQ0_B  BI  = M_D_CPU1_SB_DQ<0>
  101  VSS44  POWER  = GND
  102  DQ1_B  BI  = M_D_CPU1_SB_DQ<1>
  103  VSS45  POWER  = GND
  104  DQS0_B_T  BI  = M_D_CPU1_SB_DQS_DP<0>
  105  DQS0_B_C  BI  = M_D_CPU1_SB_DQS_DN<0>
  106  VSS46  POWER  = GND
  107  DQ4_B  BI  = M_D_CPU1_SB_DQ<4>
  108  VSS47  POWER  = GND
  109  DQ5_B  BI  = M_D_CPU1_SB_DQ<5>
  110  VSS48  POWER  = GND
  111  DQ8_B  BI  = M_D_CPU1_SB_DQ<8>
  112  VSS49  POWER  = GND
  113  DQ9_B  BI  = M_D_CPU1_SB_DQ<9>
  114  VSS50  POWER  = GND
  115  DQS1_B_T  BI  = M_D_CPU1_SB_DQS_DP<1>
  116  DQS1_B_C  BI  = M_D_CPU1_SB_DQS_DN<1>
  117  VSS51  POWER  = GND
  118  DQ12_B  BI  = M_D_CPU1_SB_DQ<12>
  119  VSS52  POWER  = GND
  120  DQ13_B  BI  = M_D_CPU1_SB_DQ<13>
  121  VSS53  POWER  = GND
  122  DQ16_B  BI  = M_D_CPU1_SB_DQ<16>
  123  VSS54  POWER  = GND
  124  DQ17_B  BI  = M_D_CPU1_SB_DQ<17>
  125  VSS55  POWER  = GND
  126  DQS2_B_T  BI  = M_D_CPU1_SB_DQS_DP<2>
  127  DQS2_B_C  BI  = M_D_CPU1_SB_DQS_DN<2>
  128  VSS56  POWER  = GND
  129  DQ20_B  BI  = M_D_CPU1_SB_DQ<20>
  130  VSS57  POWER  = GND
  131  DQ21_B  BI  = M_D_CPU1_SB_DQ<21>
  132  VSS58  POWER  = GND
  133  DQ24_B  BI  = M_D_CPU1_SB_DQ<24>
  134  VSS59  POWER  = GND
  135  DQ25_B  BI  = M_D_CPU1_SB_DQ<25>
  136  VSS60  POWER  = GND
  137  DQS3_B_T  BI  = M_D_CPU1_SB_DQS_DP<3>
  138  DQS3_B_C  BI  = M_D_CPU1_SB_DQS_DN<3>
  139  VSS61  POWER  = GND
  140  DQ28_B  BI  = M_D_CPU1_SB_DQ<28>
  141  VSS62  POWER  = GND
  142  DQ29_B  BI  = M_D_CPU1_SB_DQ<29>
  143  VSS63  POWER  = GND
  144  RFU1  TRI  = NC
  145  VIN_BULK1  POWER  = P12V_MEM_CPU1
  146  VIN_BULK2  POWER  = P12V_MEM_CPU1
  147  \pwr_good||fail_n\  BI  = PWRGD_CHD_CPU1_DIMM
  148  HAS  IN  = PD_CHD_CPU1_DIMM_SAA
  149  RFU2  TRI  = NC
  150  RFU3  TRI  = NC
  151  VSS64  POWER  = GND
  152  DQ2_A  BI  = M_D_CPU1_SA_DQ<2>
  153  VSS65  POWER  = GND
  154  DQ3_A  BI  = M_D_CPU1_SA_DQ<3>
  155  VSS66  POWER  = GND
  156  \dqs5_a_c||tdqs5_a_c||dqs5_a_t||tdqs5_a_t\  BI  = M_D_CPU1_SA_DQS_DN<5>
  157  \dqs5_a_t||tdqs5_a_t\  BI  = M_D_CPU1_SA_DQS_DP<5>
  158  VSS67  POWER  = GND
  159  DQ6_A  BI  = M_D_CPU1_SA_DQ<6>
  160  VSS68  POWER  = GND
  161  DQ7_A  BI  = M_D_CPU1_SA_DQ<7>
  162  VSS69  POWER  = GND
  163  DQ10_A  BI  = M_D_CPU1_SA_DQ<10>
  164  VSS70  POWER  = GND
  165  DQ11_A  BI  = M_D_CPU1_SA_DQ<11>
  166  VSS71  POWER  = GND
  167  \dqs6_a_c||tdqs6_a_c||dqs6_a_t||tdqs6_a_t\  BI  = M_D_CPU1_SA_DQS_DN<6>
  168  \dqs6_a_t||tdqs6_a_t\  BI  = M_D_CPU1_SA_DQS_DP<6>
  169  VSS72  POWER  = GND
  170  DQ14_A  BI  = M_D_CPU1_SA_DQ<14>
  171  VSS73  POWER  = GND
  172  DQ15_A  BI  = M_D_CPU1_SA_DQ<15>
  173  VSS74  POWER  = GND
  174  DQ18_A  BI  = M_D_CPU1_SA_DQ<18>
  175  VSS75  POWER  = GND
  176  DQ19_A  BI  = M_D_CPU1_SA_DQ<19>
  177  VSS76  POWER  = GND
  178  \dqs7_a_c||tdqs7_a_c\  BI  = M_D_CPU1_SA_DQS_DN<7>
  179  \dqs7_a_t||tdqs7_a_t\  BI  = M_D_CPU1_SA_DQS_DP<7>
  180  VSS77  POWER  = GND
  181  DQ22_A  BI  = M_D_CPU1_SA_DQ<22>
  182  VSS78  POWER  = GND
  183  DQ23_A  BI  = M_D_CPU1_SA_DQ<23>
  184  VSS79  POWER  = GND
  185  DQ26_A  BI  = M_D_CPU1_SA_DQ<26>
  186  VSS80  POWER  = GND
  187  DQ27_A  BI  = M_D_CPU1_SA_DQ<27>
  188  VSS81  POWER  = GND
  189  \dqs8_a_c||tdqs8_a_c\  BI  = M_D_CPU1_SA_DQS_DN<8>
  190  \dqs8_a_t||tdqs8_a_t\  BI  = M_D_CPU1_SA_DQS_DP<8>
  191  VSS82  POWER  = GND
  192  DQ30_A  BI  = M_D_CPU1_SA_DQ<30>
  193  VSS83  POWER  = GND
  194  DQ31_A  BI  = M_D_CPU1_SA_DQ<31>
  195  VSS84  POWER  = GND
  196  CB2_A  BI  = M_D_CPU1_SA_CB<2>
  197  VSS85  POWER  = GND
  198  CB3_A  BI  = M_D_CPU1_SA_CB<3>
  199  VSS86  POWER  = GND
  200  \dqs9_a_c||tdqs9_a_c\  BI  = M_D_CPU1_SA_DQS_DN<9>
  201  \dqs9_a_t||tdqs9_a_t\  BI  = M_D_CPU1_SA_DQS_DP<9>
  202  VSS87  POWER  = GND
  203  CB6_A  BI  = M_D_CPU1_SA_CB<6>
  204  VSS88  POWER  = GND
  205  CB7_A  BI  = M_D_CPU1_SA_CB<7>
  206  VSS89  POWER  = GND
  207  RESET_N  IN  = M_D_CPU1_RESET_N
  208  VSS90  POWER  = GND
  209  CS1_A_N  IN  = M_D_CPU1_SA_CS_N<1>
  210  VSS91  POWER  = GND
  211  CA1_A  IN  = M_D_CPU1_SA_CA<1>
  212  VSS92  POWER  = GND
  213  CA3_A  IN  = M_D_CPU1_SA_CA<3>
  214  VSS93  POWER  = GND
  215  CA5_A  IN  = M_D_CPU1_SA_CA<5>
  216  VSS94  POWER  = GND
  217  CK_T  IN  = M_D_CPU1_CLK_DP<0>
  218  CK_C  IN  = M_D_CPU1_CLK_DN<0>
  219  VSS95  POWER  = GND
  220  RFU4  TRI  = NC
  221  CA1_B  IN  = M_D_CPU1_SB_CA<1>
  222  VSS96  POWER  = GND
  223  CA3_B  IN  = M_D_CPU1_SB_CA<3>
  224  VSS97  POWER  = GND
  225  CA5_B  IN  = M_D_CPU1_SB_CA<5>
  226  VSS98  POWER  = GND
  227  PAR_B  IN  = M_D_CPU1_SB_PAR
  228  VSS99  POWER  = GND
  229  CS1_B_N  IN  = M_D_CPU1_SB_CS_N<1>
  230  VSS100  POWER  = GND
  231  RFU5  TRI  = NC
  232  RFU6  TRI  = NC
  233  VSS101  POWER  = GND
  234  CB6_B  BI  = M_D_CPU1_SB_CB<6>
  235  VSS102  POWER  = GND
  236  CB7_B  BI  = M_D_CPU1_SB_CB<7>
  237  VSS103  POWER  = GND
  238  DQS4_B_C  BI  = M_D_CPU1_SB_DQS_DN<4>
  239  DQS4_B_T  BI  = M_D_CPU1_SB_DQS_DP<4>
  240  VSS104  POWER  = GND
  241  CB2_B  BI  = M_D_CPU1_SB_CB<2>
  242  VSS105  POWER  = GND
  243  CB3_B  BI  = M_D_CPU1_SB_CB<3>
  244  VSS106  POWER  = GND
  245  DQ2_B  BI  = M_D_CPU1_SB_DQ<2>
  246  VSS107  POWER  = GND
  247  DQ3_B  BI  = M_D_CPU1_SB_DQ<3>
  248  VSS108  POWER  = GND
  249  \dqs5_b_c||tdqs5_b_c\  BI  = M_D_CPU1_SB_DQS_DN<5>
  250  \dqs5_b_t||tdqs5_b_t\  BI  = M_D_CPU1_SB_DQS_DP<5>
  251  VSS109  POWER  = GND
  252  DQ6_B  BI  = M_D_CPU1_SB_DQ<6>
  253  VSS110  POWER  = GND
  254  DQ7_B  BI  = M_D_CPU1_SB_DQ<7>
  255  VSS111  POWER  = GND
  256  DQ10_B  BI  = M_D_CPU1_SB_DQ<10>
  257  VSS112  POWER  = GND
  258  DQ11_B  BI  = M_D_CPU1_SB_DQ<11>
  259  VSS113  POWER  = GND
  260  \dqs6_b_c||tdqs6_b_c\  BI  = M_D_CPU1_SB_DQS_DN<6>
  261  \dqs6_b_t||tdqs6_b_t\  BI  = M_D_CPU1_SB_DQS_DP<6>
  262  VSS114  POWER  = GND
  263  DQ14_B  BI  = M_D_CPU1_SB_DQ<14>
  264  VSS115  POWER  = GND
  265  DQ15_B  BI  = M_D_CPU1_SB_DQ<15>
  266  VSS116  POWER  = GND
  267  DQ18_B  BI  = M_D_CPU1_SB_DQ<18>
  268  VSS117  POWER  = GND
  269  DQ19_B  BI  = M_D_CPU1_SB_DQ<19>
  270  VSS118  POWER  = GND
  271  \dqs7_b_c||tdqs7_b_c\  BI  = M_D_CPU1_SB_DQS_DN<7>
  272  \dqs7_b_t||tdqs7_b_t\  BI  = M_D_CPU1_SB_DQS_DP<7>
  273  VSS119  POWER  = GND
  274  DQ22_B  BI  = M_D_CPU1_SB_DQ<22>
  275  VSS120  POWER  = GND
  276  DQ23_B  BI  = M_D_CPU1_SB_DQ<23>
  277  VSS121  POWER  = GND
  278  DQ26_B  BI  = M_D_CPU1_SB_DQ<26>
  279  VSS122  POWER  = GND
  280  DQ27_B  BI  = M_D_CPU1_SB_DQ<27>
  281  VSS123  POWER  = GND
  282  \dqs8_b_c||tdqs8_b_c\  BI  = M_D_CPU1_SB_DQS_DN<8>
  283  \dqs8_b_t||tdqs8_b_t\  BI  = M_D_CPU1_SB_DQS_DP<8>
  284  VSS124  POWER  = GND
  285  DQ30_B  BI  = M_D_CPU1_SB_DQ<30>
  286  VSS125  POWER  = GND
  287  DQ31_B  BI  = M_D_CPU1_SB_DQ<31>
  288  VSS126  POWER  = GND
  G1  G1  POWER  = GND
  G2  G2  POWER  = GND
  G3  G3  POWER  = GND
